(kicad_pcb
	(version 20260206)
	(generator "pcbnew")
	(generator_version "10.0")
	(general
		(thickness 1.6)
		(legacy_teardrops no)
	)
	(paper "A4")
	(title_block
		(title "03242023_DA0F0TMBIJ0_F0T_Motherboard_J_brd_V01_OCP.brd")
		(comment 1 "Grand Teton / footprints 3419-3424 of 6105")
	)
	(layers
		(0 "F.Cu" signal "TOP")
		(4 "In1.Cu" signal "GND")
		(6 "In2.Cu" signal "IN1")
		(8 "In3.Cu" signal "GND1")
		(10 "In4.Cu" signal "IN2")
		(12 "In5.Cu" signal "GND2")
		(14 "In6.Cu" signal "IN3")
		(16 "In7.Cu" signal "GND3")
		(18 "In8.Cu" signal "VCC")
		(20 "In9.Cu" signal "VCC1")
		(22 "In10.Cu" signal "GND4")
		(24 "In11.Cu" signal "IN4")
		(26 "In12.Cu" signal "GND5")
		(28 "In13.Cu" signal "IN5")
		(30 "In14.Cu" signal "GND6")
		(32 "In15.Cu" signal "IN6")
		(34 "In16.Cu" signal "GND7")
		(2 "B.Cu" signal "BOTTOM")
		(9 "F.Adhes" user "F.Adhesive")
		(11 "B.Adhes" user "B.Adhesive")
		(13 "F.Paste" user "Package Geometry/Pastemask Top")
		(15 "B.Paste" user "Package Geometry/Pastemask Bottom")
		(5 "F.SilkS" user "Ref Des/Silkscreen Top")
		(7 "B.SilkS" user "Ref Des/Silkscreen Bottom")
		(1 "F.Mask" user "Board Geometry/Soldermask Top")
		(3 "B.Mask" user "Board Geometry/Soldermask Bottom")
		(17 "Dwgs.User" user "User.Drawings")
		(19 "Cmts.User" user "User.Comments")
		(21 "Eco1.User" user "User.Eco1")
		(23 "Eco2.User" user "User.Eco2")
		(25 "Edge.Cuts" user "Board Geometry/Outline")
		(27 "Margin" user)
		(31 "F.CrtYd" user "Package Geometry/Place Bound Top")
		(29 "B.CrtYd" user "Package Geometry/Place Bound Bottom")
		(35 "F.Fab" user "Ref Des/Assembly Top")
		(33 "B.Fab" user "Ref Des/Assembly Bottom")
	)
	(footprint ""
		(layer "F.Cu")
		(at 447.557652 -17.433798 180)
		(property "Reference" "PR3788"
			(at 0 0 180)
			(layer "F.SilkS")
			(hide yes)
			(effects
				(font
					(size 1.27 1.27)
				)
			)
		)
		(property "Value" ""
			(at 0 0 180)
			(layer "F.Fab")
			(effects
				(font
					(size 1.27 1.27)
				)
			)
		)
		(duplicate_pad_numbers_are_jumpers no)
		(fp_line
			(start 0.7874 0.4064)
			(end -0.7874 0.4064)
			(stroke
				(width 0.1524)
				(type default)
			)
			(layer "F.SilkS")
		)
		(fp_line
			(start 0.7874 -0.4064)
			(end 0.7874 0.4064)
			(stroke
				(width 0.1524)
				(type default)
			)
			(layer "F.SilkS")
		)
		(fp_line
			(start -0.7874 0.4064)
			(end -0.7874 -0.4064)
			(stroke
				(width 0.1524)
				(type default)
			)
			(layer "F.SilkS")
		)
		(fp_line
			(start -0.7874 -0.4064)
			(end 0.7874 -0.4064)
			(stroke
				(width 0.1524)
				(type default)
			)
			(layer "F.SilkS")
		)
		(fp_line
			(start 0.67945 0.3048)
			(end 0.120396 0.3048)
			(stroke
				(width 0.1)
				(type default)
			)
			(layer "F.Fab")
		)
		(fp_line
			(start 0.67945 -0.3048)
			(end 0.67945 0.3048)
			(stroke
				(width 0.1)
				(type default)
			)
			(layer "F.Fab")
		)
		(fp_line
			(start 0.12065 -0.2794)
			(end 0.12065 -0.3048)
			(stroke
				(width 0.1)
				(type default)
			)
			(layer "F.Fab")
		)
		(fp_line
			(start 0.12065 -0.3048)
			(end 0.67945 -0.3048)
			(stroke
				(width 0.1)
				(type default)
			)
			(layer "F.Fab")
		)
		(fp_line
			(start 0.120396 0.3048)
			(end 0.120396 0.2794)
			(stroke
				(width 0.1)
				(type default)
			)
			(layer "F.Fab")
		)
		(fp_line
			(start 0.120396 0.2794)
			(end -0.12065 0.2794)
			(stroke
				(width 0.1)
				(type default)
			)
			(layer "F.Fab")
		)
		(fp_line
			(start -0.12065 0.3048)
			(end -0.67945 0.3048)
			(stroke
				(width 0.1)
				(type default)
			)
			(layer "F.Fab")
		)
		(fp_line
			(start -0.12065 0.2794)
			(end -0.12065 0.3048)
			(stroke
				(width 0.1)
				(type default)
			)
			(layer "F.Fab")
		)
		(fp_line
			(start -0.12065 -0.2794)
			(end 0.12065 -0.2794)
			(stroke
				(width 0.1)
				(type default)
			)
			(layer "F.Fab")
		)
		(fp_line
			(start -0.12065 -0.305054)
			(end -0.12065 -0.2794)
			(stroke
				(width 0.1)
				(type default)
			)
			(layer "F.Fab")
		)
		(fp_line
			(start -0.67945 0.3048)
			(end -0.67945 -0.305054)
			(stroke
				(width 0.1)
				(type default)
			)
			(layer "F.Fab")
		)
		(fp_line
			(start -0.67945 -0.305054)
			(end -0.12065 -0.305054)
			(stroke
				(width 0.1)
				(type default)
			)
			(layer "F.Fab")
		)
		(pad "1" smd circle
			(at -0.40005 0 180)
			(size 0 0)
			(layers "F.Cu" "F.Mask" "F.Paste")
			(net "P12V_OCP_OV_1")
		)
		(pad "2" smd circle
			(at 0.40005 0 180)
			(size 0 0)
			(layers "F.Cu" "F.Mask" "F.Paste")
			(net "GND")
		)
	)
	(footprint ""
		(layer "F.Cu")
		(at 376.888248 -361.313476 180)
		(property "Reference" "PR1335"
			(at 0 0 180)
			(layer "F.SilkS")
			(hide yes)
			(effects
				(font
					(size 1.27 1.27)
				)
			)
		)
		(property "Value" ""
			(at 0 0 180)
			(layer "F.Fab")
			(effects
				(font
					(size 1.27 1.27)
				)
			)
		)
		(duplicate_pad_numbers_are_jumpers no)
		(fp_line
			(start 0.7874 0.4064)
			(end -0.7874 0.4064)
			(stroke
				(width 0.1524)
				(type default)
			)
			(layer "F.SilkS")
		)
		(fp_line
			(start 0.7874 -0.4064)
			(end 0.7874 0.4064)
			(stroke
				(width 0.1524)
				(type default)
			)
			(layer "F.SilkS")
		)
		(fp_line
			(start -0.7874 0.4064)
			(end -0.7874 -0.4064)
			(stroke
				(width 0.1524)
				(type default)
			)
			(layer "F.SilkS")
		)
		(fp_line
			(start -0.7874 -0.4064)
			(end 0.7874 -0.4064)
			(stroke
				(width 0.1524)
				(type default)
			)
			(layer "F.SilkS")
		)
		(fp_line
			(start 0.67945 0.3048)
			(end 0.120396 0.3048)
			(stroke
				(width 0.1)
				(type default)
			)
			(layer "F.Fab")
		)
		(fp_line
			(start 0.67945 -0.3048)
			(end 0.67945 0.3048)
			(stroke
				(width 0.1)
				(type default)
			)
			(layer "F.Fab")
		)
		(fp_line
			(start 0.12065 -0.2794)
			(end 0.12065 -0.3048)
			(stroke
				(width 0.1)
				(type default)
			)
			(layer "F.Fab")
		)
		(fp_line
			(start 0.12065 -0.3048)
			(end 0.67945 -0.3048)
			(stroke
				(width 0.1)
				(type default)
			)
			(layer "F.Fab")
		)
		(fp_line
			(start 0.120396 0.3048)
			(end 0.120396 0.2794)
			(stroke
				(width 0.1)
				(type default)
			)
			(layer "F.Fab")
		)
		(fp_line
			(start 0.120396 0.2794)
			(end -0.12065 0.2794)
			(stroke
				(width 0.1)
				(type default)
			)
			(layer "F.Fab")
		)
		(fp_line
			(start -0.12065 0.3048)
			(end -0.67945 0.3048)
			(stroke
				(width 0.1)
				(type default)
			)
			(layer "F.Fab")
		)
		(fp_line
			(start -0.12065 0.2794)
			(end -0.12065 0.3048)
			(stroke
				(width 0.1)
				(type default)
			)
			(layer "F.Fab")
		)
		(fp_line
			(start -0.12065 -0.2794)
			(end 0.12065 -0.2794)
			(stroke
				(width 0.1)
				(type default)
			)
			(layer "F.Fab")
		)
		(fp_line
			(start -0.12065 -0.305054)
			(end -0.12065 -0.2794)
			(stroke
				(width 0.1)
				(type default)
			)
			(layer "F.Fab")
		)
		(fp_line
			(start -0.67945 0.3048)
			(end -0.67945 -0.305054)
			(stroke
				(width 0.1)
				(type default)
			)
			(layer "F.Fab")
		)
		(fp_line
			(start -0.67945 -0.305054)
			(end -0.12065 -0.305054)
			(stroke
				(width 0.1)
				(type default)
			)
			(layer "F.Fab")
		)
		(pad "1" smd circle
			(at -0.40005 0 180)
			(size 0 0)
			(layers "F.Cu" "F.Mask" "F.Paste")
			(net "P3V3_AUX")
		)
		(pad "2" smd circle
			(at 0.40005 0 180)
			(size 0 0)
			(layers "F.Cu" "F.Mask" "F.Paste")
			(net "PVPP_HBM_CPU0_VCC")
		)
	)
	(footprint ""
		(layer "F.Cu")
		(at 38.02888 -435.955948 180)
		(property "Reference" "R2897"
			(at 0 0 180)
			(layer "F.SilkS")
			(hide yes)
			(effects
				(font
					(size 1.27 1.27)
				)
			)
		)
		(property "Value" ""
			(at 0 0 180)
			(layer "F.Fab")
			(effects
				(font
					(size 1.27 1.27)
				)
			)
		)
		(duplicate_pad_numbers_are_jumpers no)
		(fp_line
			(start 0.7874 0.4064)
			(end -0.7874 0.4064)
			(stroke
				(width 0.1524)
				(type default)
			)
			(layer "F.SilkS")
		)
		(fp_line
			(start 0.7874 -0.4064)
			(end 0.7874 0.4064)
			(stroke
				(width 0.1524)
				(type default)
			)
			(layer "F.SilkS")
		)
		(fp_line
			(start -0.7874 0.4064)
			(end -0.7874 -0.4064)
			(stroke
				(width 0.1524)
				(type default)
			)
			(layer "F.SilkS")
		)
		(fp_line
			(start -0.7874 -0.4064)
			(end 0.7874 -0.4064)
			(stroke
				(width 0.1524)
				(type default)
			)
			(layer "F.SilkS")
		)
		(fp_line
			(start 0.67945 0.3048)
			(end 0.120396 0.3048)
			(stroke
				(width 0.1)
				(type default)
			)
			(layer "F.Fab")
		)
		(fp_line
			(start 0.67945 -0.3048)
			(end 0.67945 0.3048)
			(stroke
				(width 0.1)
				(type default)
			)
			(layer "F.Fab")
		)
		(fp_line
			(start 0.12065 -0.2794)
			(end 0.12065 -0.3048)
			(stroke
				(width 0.1)
				(type default)
			)
			(layer "F.Fab")
		)
		(fp_line
			(start 0.12065 -0.3048)
			(end 0.67945 -0.3048)
			(stroke
				(width 0.1)
				(type default)
			)
			(layer "F.Fab")
		)
		(fp_line
			(start 0.120396 0.3048)
			(end 0.120396 0.2794)
			(stroke
				(width 0.1)
				(type default)
			)
			(layer "F.Fab")
		)
		(fp_line
			(start 0.120396 0.2794)
			(end -0.12065 0.2794)
			(stroke
				(width 0.1)
				(type default)
			)
			(layer "F.Fab")
		)
		(fp_line
			(start -0.12065 0.3048)
			(end -0.67945 0.3048)
			(stroke
				(width 0.1)
				(type default)
			)
			(layer "F.Fab")
		)
		(fp_line
			(start -0.12065 0.2794)
			(end -0.12065 0.3048)
			(stroke
				(width 0.1)
				(type default)
			)
			(layer "F.Fab")
		)
		(fp_line
			(start -0.12065 -0.2794)
			(end 0.12065 -0.2794)
			(stroke
				(width 0.1)
				(type default)
			)
			(layer "F.Fab")
		)
		(fp_line
			(start -0.12065 -0.305054)
			(end -0.12065 -0.2794)
			(stroke
				(width 0.1)
				(type default)
			)
			(layer "F.Fab")
		)
		(fp_line
			(start -0.67945 0.3048)
			(end -0.67945 -0.305054)
			(stroke
				(width 0.1)
				(type default)
			)
			(layer "F.Fab")
		)
		(fp_line
			(start -0.67945 -0.305054)
			(end -0.12065 -0.305054)
			(stroke
				(width 0.1)
				(type default)
			)
			(layer "F.Fab")
		)
		(pad "1" smd circle
			(at -0.40005 0 180)
			(size 0 0)
			(layers "F.Cu" "F.Mask" "F.Paste")
			(net "SMB_1_BMC_GPU_BUF_R_SCL")
		)
		(pad "2" smd circle
			(at 0.40005 0 180)
			(size 0 0)
			(layers "F.Cu" "F.Mask" "F.Paste")
			(net "SMB_1_BMC_GPU_BUF_SCL")
		)
	)
	(footprint ""
		(layer "F.Cu")
		(at 164.52215 -418.514276 90)
		(property "Reference" "R2669"
			(at 0 0 90)
			(layer "F.SilkS")
			(hide yes)
			(effects
				(font
					(size 1.27 1.27)
				)
			)
		)
		(property "Value" ""
			(at 0 0 90)
			(layer "F.Fab")
			(effects
				(font
					(size 1.27 1.27)
				)
			)
		)
		(duplicate_pad_numbers_are_jumpers no)
		(fp_line
			(start 0.7874 -0.4064)
			(end 0.7874 0.4064)
			(stroke
				(width 0.1524)
				(type default)
			)
			(layer "F.SilkS")
		)
		(fp_line
			(start -0.7874 -0.4064)
			(end 0.7874 -0.4064)
			(stroke
				(width 0.1524)
				(type default)
			)
			(layer "F.SilkS")
		)
		(fp_line
			(start 0.7874 0.4064)
			(end -0.7874 0.4064)
			(stroke
				(width 0.1524)
				(type default)
			)
			(layer "F.SilkS")
		)
		(fp_line
			(start -0.7874 0.4064)
			(end -0.7874 -0.4064)
			(stroke
				(width 0.1524)
				(type default)
			)
			(layer "F.SilkS")
		)
		(fp_line
			(start -0.12065 -0.305054)
			(end -0.12065 -0.2794)
			(stroke
				(width 0.1)
				(type default)
			)
			(layer "F.Fab")
		)
		(fp_line
			(start -0.67945 -0.305054)
			(end -0.12065 -0.305054)
			(stroke
				(width 0.1)
				(type default)
			)
			(layer "F.Fab")
		)
		(fp_line
			(start 0.67945 -0.3048)
			(end 0.67945 0.3048)
			(stroke
				(width 0.1)
				(type default)
			)
			(layer "F.Fab")
		)
		(fp_line
			(start 0.12065 -0.3048)
			(end 0.67945 -0.3048)
			(stroke
				(width 0.1)
				(type default)
			)
			(layer "F.Fab")
		)
		(fp_line
			(start 0.12065 -0.2794)
			(end 0.12065 -0.3048)
			(stroke
				(width 0.1)
				(type default)
			)
			(layer "F.Fab")
		)
		(fp_line
			(start -0.12065 -0.2794)
			(end 0.12065 -0.2794)
			(stroke
				(width 0.1)
				(type default)
			)
			(layer "F.Fab")
		)
		(fp_line
			(start 0.120396 0.2794)
			(end -0.12065 0.2794)
			(stroke
				(width 0.1)
				(type default)
			)
			(layer "F.Fab")
		)
		(fp_line
			(start -0.12065 0.2794)
			(end -0.12065 0.3048)
			(stroke
				(width 0.1)
				(type default)
			)
			(layer "F.Fab")
		)
		(fp_line
			(start 0.67945 0.3048)
			(end 0.120396 0.3048)
			(stroke
				(width 0.1)
				(type default)
			)
			(layer "F.Fab")
		)
		(fp_line
			(start 0.120396 0.3048)
			(end 0.120396 0.2794)
			(stroke
				(width 0.1)
				(type default)
			)
			(layer "F.Fab")
		)
		(fp_line
			(start -0.12065 0.3048)
			(end -0.67945 0.3048)
			(stroke
				(width 0.1)
				(type default)
			)
			(layer "F.Fab")
		)
		(fp_line
			(start -0.67945 0.3048)
			(end -0.67945 -0.305054)
			(stroke
				(width 0.1)
				(type default)
			)
			(layer "F.Fab")
		)
		(pad "1" smd circle
			(at -0.40005 0 90)
			(size 0 0)
			(layers "F.Cu" "F.Mask" "F.Paste")
			(net "P3V3_AUX")
		)
		(pad "2" smd circle
			(at 0.40005 0 90)
			(size 0 0)
			(layers "F.Cu" "F.Mask" "F.Paste")
			(net "SMB_BMC_SWB_BUF_R_SDA")
		)
	)
	(footprint ""
		(layer "F.Cu")
		(at 424.204892 -379.313948)
		(property "Reference" "R2919"
			(at 0 0 0)
			(layer "F.SilkS")
			(hide yes)
			(effects
				(font
					(size 1.27 1.27)
				)
			)
		)
		(property "Value" ""
			(at 0 0 0)
			(layer "F.Fab")
			(effects
				(font
					(size 1.27 1.27)
				)
			)
		)
		(duplicate_pad_numbers_are_jumpers no)
		(fp_line
			(start -0.7874 -0.4064)
			(end 0.7874 -0.4064)
			(stroke
				(width 0.1524)
				(type default)
			)
			(layer "F.SilkS")
		)
		(fp_line
			(start -0.7874 0.4064)
			(end -0.7874 -0.4064)
			(stroke
				(width 0.1524)
				(type default)
			)
			(layer "F.SilkS")
		)
		(fp_line
			(start 0.7874 -0.4064)
			(end 0.7874 0.4064)
			(stroke
				(width 0.1524)
				(type default)
			)
			(layer "F.SilkS")
		)
		(fp_line
			(start 0.7874 0.4064)
			(end -0.7874 0.4064)
			(stroke
				(width 0.1524)
				(type default)
			)
			(layer "F.SilkS")
		)
		(fp_line
			(start -0.67945 -0.305054)
			(end -0.12065 -0.305054)
			(stroke
				(width 0.1)
				(type default)
			)
			(layer "F.Fab")
		)
		(fp_line
			(start -0.67945 0.3048)
			(end -0.67945 -0.305054)
			(stroke
				(width 0.1)
				(type default)
			)
			(layer "F.Fab")
		)
		(fp_line
			(start -0.12065 -0.305054)
			(end -0.12065 -0.2794)
			(stroke
				(width 0.1)
				(type default)
			)
			(layer "F.Fab")
		)
		(fp_line
			(start -0.12065 -0.2794)
			(end 0.12065 -0.2794)
			(stroke
				(width 0.1)
				(type default)
			)
			(layer "F.Fab")
		)
		(fp_line
			(start -0.12065 0.2794)
			(end -0.12065 0.3048)
			(stroke
				(width 0.1)
				(type default)
			)
			(layer "F.Fab")
		)
		(fp_line
			(start -0.12065 0.3048)
			(end -0.67945 0.3048)
			(stroke
				(width 0.1)
				(type default)
			)
			(layer "F.Fab")
		)
		(fp_line
			(start 0.120396 0.2794)
			(end -0.12065 0.2794)
			(stroke
				(width 0.1)
				(type default)
			)
			(layer "F.Fab")
		)
		(fp_line
			(start 0.120396 0.3048)
			(end 0.120396 0.2794)
			(stroke
				(width 0.1)
				(type default)
			)
			(layer "F.Fab")
		)
		(fp_line
			(start 0.12065 -0.3048)
			(end 0.67945 -0.3048)
			(stroke
				(width 0.1)
				(type default)
			)
			(layer "F.Fab")
		)
		(fp_line
			(start 0.12065 -0.2794)
			(end 0.12065 -0.3048)
			(stroke
				(width 0.1)
				(type default)
			)
			(layer "F.Fab")
		)
		(fp_line
			(start 0.67945 -0.3048)
			(end 0.67945 0.3048)
			(stroke
				(width 0.1)
				(type default)
			)
			(layer "F.Fab")
		)
		(fp_line
			(start 0.67945 0.3048)
			(end 0.120396 0.3048)
			(stroke
				(width 0.1)
				(type default)
			)
			(layer "F.Fab")
		)
		(pad "1" smd circle
			(at -0.40005 0)
			(size 0 0)
			(layers "F.Cu" "F.Mask" "F.Paste")
			(net "P3V3_AUX")
		)
		(pad "2" smd circle
			(at 0.40005 0)
			(size 0 0)
			(layers "F.Cu" "F.Mask" "F.Paste")
			(net "RST_BMC_FROM_SWB_ISO_N")
		)
	)
	(footprint ""
		(layer "F.Cu")
		(at 165.301676 -131.980178 -90)
		(property "Reference" "R1654"
			(at 0 0 270)
			(layer "F.SilkS")
			(hide yes)
			(effects
				(font
					(size 1.27 1.27)
				)
			)
		)
		(property "Value" ""
			(at 0 0 270)
			(layer "F.Fab")
			(effects
				(font
					(size 1.27 1.27)
				)
			)
		)
		(duplicate_pad_numbers_are_jumpers no)
		(fp_line
			(start -0.7874 0.4064)
			(end -0.7874 -0.4064)
			(stroke
				(width 0.1524)
				(type default)
			)
			(layer "F.SilkS")
		)
		(fp_line
			(start 0.7874 0.4064)
			(end -0.7874 0.4064)
			(stroke
				(width 0.1524)
				(type default)
			)
			(layer "F.SilkS")
		)
		(fp_line
			(start -0.7874 -0.4064)
			(end 0.7874 -0.4064)
			(stroke
				(width 0.1524)
				(type default)
			)
			(layer "F.SilkS")
		)
		(fp_line
			(start 0.7874 -0.4064)
			(end 0.7874 0.4064)
			(stroke
				(width 0.1524)
				(type default)
			)
			(layer "F.SilkS")
		)
		(fp_line
			(start -0.67945 0.3048)
			(end -0.67945 -0.305054)
			(stroke
				(width 0.1)
				(type default)
			)
			(layer "F.Fab")
		)
		(fp_line
			(start -0.12065 0.3048)
			(end -0.67945 0.3048)
			(stroke
				(width 0.1)
				(type default)
			)
			(layer "F.Fab")
		)
		(fp_line
			(start 0.120396 0.3048)
			(end 0.120396 0.2794)
			(stroke
				(width 0.1)
				(type default)
			)
			(layer "F.Fab")
		)
		(fp_line
			(start 0.67945 0.3048)
			(end 0.120396 0.3048)
			(stroke
				(width 0.1)
				(type default)
			)
			(layer "F.Fab")
		)
		(fp_line
			(start -0.12065 0.2794)
			(end -0.12065 0.3048)
			(stroke
				(width 0.1)
				(type default)
			)
			(layer "F.Fab")
		)
		(fp_line
			(start 0.120396 0.2794)
			(end -0.12065 0.2794)
			(stroke
				(width 0.1)
				(type default)
			)
			(layer "F.Fab")
		)
		(fp_line
			(start -0.12065 -0.2794)
			(end 0.12065 -0.2794)
			(stroke
				(width 0.1)
				(type default)
			)
			(layer "F.Fab")
		)
		(fp_line
			(start 0.12065 -0.2794)
			(end 0.12065 -0.3048)
			(stroke
				(width 0.1)
				(type default)
			)
			(layer "F.Fab")
		)
		(fp_line
			(start 0.12065 -0.3048)
			(end 0.67945 -0.3048)
			(stroke
				(width 0.1)
				(type default)
			)
			(layer "F.Fab")
		)
		(fp_line
			(start 0.67945 -0.3048)
			(end 0.67945 0.3048)
			(stroke
				(width 0.1)
				(type default)
			)
			(layer "F.Fab")
		)
		(fp_line
			(start -0.67945 -0.305054)
			(end -0.12065 -0.305054)
			(stroke
				(width 0.1)
				(type default)
			)
			(layer "F.Fab")
		)
		(fp_line
			(start -0.12065 -0.305054)
			(end -0.12065 -0.2794)
			(stroke
				(width 0.1)
				(type default)
			)
			(layer "F.Fab")
		)
		(pad "1" smd circle
			(at -0.40005 0 270)
			(size 0 0)
			(layers "F.Cu" "F.Mask" "F.Paste")
			(net "VR_P5V_EN_D_R")
		)
		(pad "2" smd circle
			(at 0.40005 0 270)
			(size 0 0)
			(layers "F.Cu" "F.Mask" "F.Paste")
			(net "VR_P5V_EN_D_R1")
		)
	)
)
